(kicad_pcb
	(version 20221018)
	(generator pcbnew)
	(general
    (thickness 0.908)
  )
	(paper "A4")
	(title_block
    (title "HDMI-MIPI Bridge")
    (date "2024-04-24")
    (rev "1.3.2")
		(comment 9 "footprints 3-4 of 121")
	)
	(layers
    (0 "F.Cu" signal)
    (1 "In1.Cu" signal)
    (2 "In2.Cu" signal)
    (31 "B.Cu" signal)
    (32 "B.Adhes" user "B.Adhesive")
    (33 "F.Adhes" user "F.Adhesive")
    (34 "B.Paste" user)
    (35 "F.Paste" user)
    (36 "B.SilkS" user "B.Silkscreen")
    (37 "F.SilkS" user "F.Silkscreen")
    (38 "B.Mask" user)
    (39 "F.Mask" user)
    (40 "Dwgs.User" user "User.Drawings")
    (41 "Cmts.User" user "User.Comments")
    (42 "Eco1.User" user "User.Eco1")
    (43 "Eco2.User" user "User.Eco2")
    (44 "Edge.Cuts" user)
    (45 "Margin" user)
    (46 "B.CrtYd" user "B.Courtyard")
    (47 "F.CrtYd" user "F.Courtyard")
    (48 "B.Fab" user)
    (49 "F.Fab" user)
  )
	(footprint "antmicro-footprints:BGA-64_8x8_6.0x6.0mm" locked (layer "F.Cu")
    (at 135.4239 110.4001 -90)
    (property "Author" "Antmicro")
    (property "License" "Apache-2.0")
    (property "MPN" "TC358743XBG")
    (property "Manufacturer" "Toshiba")
    (property "Sheetfile" "channel1.kicad_sch")
    (property "Sheetname" "Channel 1")
    (property "ki_description" "HDMI to MIPI CSI-2 bridge. Supports HDMI 1.4. MIPI CSI-2 compliant. 80-Pin VFBGA")
    (property "ki_keywords" "SMT, INTERFACE, IC, CONTROLLER")
    (attr smd)
    (fp_text reference "U1" (at -3.3001 1.5239) (layer "F.SilkS")
        (effects (font (size 0.65 0.65) (thickness 0.13)) (justify left bottom))
    )
    (fp_text value "TC358743XBG" (at -7.0104 4.8768 90) (layer "F.Fab")
        (effects (font (size 0.65 0.65) (thickness 0.13)) (justify right bottom))
    )
    (fp_text user "Author: Antmicro" (at -9 7.2 90) (layer "F.Fab") hide
        (effects (font (size 0.7 0.7) (thickness 0.15)) (justify right bottom))
    )
    (fp_text user "License: Apache-2.0" (at -9 8.4 90) (layer "F.Fab") hide
        (effects (font (size 0.7 0.7) (thickness 0.15)) (justify right bottom))
    )
    (fp_text user "${REFERENCE}" (at -9 5.999 90) (layer "F.Fab") hide
        (effects (font (size 0.7 0.7) (thickness 0.15)) (justify right bottom))
    )
    (fp_line (start -3.121 -2) (end -3.121 -1.621)
      (stroke (width 0.15) (type solid)) (layer "F.SilkS"))
    (fp_line (start -3.121 3.12) (end -3.121 1.62)
      (stroke (width 0.15) (type solid)) (layer "F.SilkS"))
    (fp_line (start -2 -3.121) (end -3.121 -2)
      (stroke (width 0.15) (type solid)) (layer "F.SilkS"))
    (fp_line (start -1.621 -3.121) (end -2 -3.121)
      (stroke (width 0.15) (type solid)) (layer "F.SilkS"))
    (fp_line (start -1.621 3.12) (end -3.121 3.12)
      (stroke (width 0.15) (type solid)) (layer "F.SilkS"))
    (fp_line (start 1.62 -3.121) (end 3.12 -3.121)
      (stroke (width 0.15) (type solid)) (layer "F.SilkS"))
    (fp_line (start 1.62 -3.121) (end 3.12 -3.121)
      (stroke (width 0.15) (type solid)) (layer "F.SilkS"))
    (fp_line (start 1.62 -3.121) (end 3.12 -3.121)
      (stroke (width 0.15) (type solid)) (layer "F.SilkS"))
    (fp_line (start 1.62 3.12) (end 3.12 3.12)
      (stroke (width 0.15) (type solid)) (layer "F.SilkS"))
    (fp_line (start 3.12 -3.121) (end 3.12 -1.621)
      (stroke (width 0.15) (type solid)) (layer "F.SilkS"))
    (fp_line (start 3.12 -3.121) (end 3.12 -1.621)
      (stroke (width 0.15) (type solid)) (layer "F.SilkS"))
    (fp_line (start 3.12 -3.121) (end 3.12 -1.621)
      (stroke (width 0.15) (type solid)) (layer "F.SilkS"))
    (fp_line (start 3.12 3.12) (end 3.12 1.62)
      (stroke (width 0.15) (type solid)) (layer "F.SilkS"))
    (fp_circle (center -3 -2.9954) (end -2.951 -2.9954)
      (stroke (width 0.15) (type solid)) (fill solid) (layer "F.SilkS"))
    (fp_line (start -3.21 -3.21) (end 3.2 -3.21)
      (stroke (width 0.05) (type solid)) (layer "F.CrtYd"))
    (fp_line (start -3.21 3.2) (end -3.21 -3.21)
      (stroke (width 0.05) (type solid)) (layer "F.CrtYd"))
    (fp_line (start 3.2 -3.21) (end 3.2 3.2)
      (stroke (width 0.05) (type solid)) (layer "F.CrtYd"))
    (fp_line (start 3.2 3.2) (end -3.21 3.2)
      (stroke (width 0.05) (type solid)) (layer "F.CrtYd"))
    (fp_line (start -3 -2) (end -3 2.999)
      (stroke (width 0.15) (type solid)) (layer "F.Fab"))
    (fp_line (start -3 2.999) (end 2.999 2.999)
      (stroke (width 0.15) (type solid)) (layer "F.Fab"))
    (fp_line (start -2 -3) (end -3 -2)
      (stroke (width 0.15) (type solid)) (layer "F.Fab"))
    (fp_line (start 2.999 -3) (end -2 -3)
      (stroke (width 0.15) (type solid)) (layer "F.Fab"))
    (fp_line (start 2.999 2.999) (end 2.999 -3)
      (stroke (width 0.15) (type solid)) (layer "F.Fab"))
    (pad "A1" smd circle locked (at -2.275 -2.275 270) (size 0.3 0.3) (layers "F.Cu" "F.Paste" "F.Mask")
      (net 113 "Net-(U1B-REXT)") (pinfunction "REXT") (pintype "input"))
    (pad "A2" smd circle locked (at -1.625 -2.275 270) (size 0.3 0.3) (layers "F.Cu" "F.Paste" "F.Mask")
      (net 2 "GND") (pinfunction "GND") (pintype "power_in"))
    (pad "A3" smd circle locked (at -0.975 -2.275 270) (size 0.3 0.3) (layers "F.Cu" "F.Paste" "F.Mask")
      (net 2 "GND") (pinfunction "VPGM") (pintype "input"))
    (pad "A4" smd circle locked (at -0.326 -2.275 270) (size 0.3 0.3) (layers "F.Cu" "F.Paste" "F.Mask")
      (net 1 "Net-(U1C-BIASDA)") (pinfunction "BIASDA") (pintype "output"))
    (pad "A5" smd circle locked (at 0.325 -2.275 270) (size 0.3 0.3) (layers "F.Cu" "F.Paste" "F.Mask")
      (net 3 "Net-(U1C-DAOUT)") (pinfunction "DAOUT") (pintype "output"))
    (pad "A6" smd circle locked (at 0.974 -2.275 270) (size 0.3 0.3) (layers "F.Cu" "F.Paste" "F.Mask")
      (net 123 "unconnected-(U1C-PFIL-PadA6)") (pinfunction "PFIL") (pintype "output+no_connect"))
    (pad "A7" smd circle locked (at 1.624 -2.275 270) (size 0.3 0.3) (layers "F.Cu" "F.Paste" "F.Mask")
      (net 48 "CSI1_D4_N") (pinfunction "CSID3_N") (pintype "output"))
    (pad "A8" smd circle locked (at 2.274 -2.275 270) (size 0.3 0.3) (layers "F.Cu" "F.Paste" "F.Mask")
      (net 49 "CSI1_D4_P") (pinfunction "CSID3_P") (pintype "output"))
    (pad "B1" smd circle locked (at -2.275 -1.625 270) (size 0.3 0.3) (layers "F.Cu" "F.Paste" "F.Mask")
      (net 100 "/Channel 1/CH1_AVDD33") (pinfunction "AVDD33") (pintype "power_in"))
    (pad "B2" smd circle locked (at -1.625 -1.625 270) (size 0.3 0.3) (layers "F.Cu" "F.Paste" "F.Mask")
      (net 6 "Net-(C5-Pad1)") (pinfunction "AVDD12") (pintype "power_in"))
    (pad "B3" smd circle locked (at -0.975 -1.625 270) (size 0.3 0.3) (layers "F.Cu" "F.Paste" "F.Mask")
      (net 124 "unconnected-(U1B-INT-PadB3)") (pinfunction "INT") (pintype "output+no_connect"))
    (pad "B4" smd circle locked (at -0.326 -1.625 270) (size 0.3 0.3) (layers "F.Cu" "F.Paste" "F.Mask")
      (net 125 "unconnected-(U1A-IR-PadB4)") (pinfunction "IR") (pintype "input+no_connect"))
    (pad "B5" smd circle locked (at 0.325 -1.625 270) (size 0.3 0.3) (layers "F.Cu" "F.Paste" "F.Mask")
      (net 5 "Net-(U1B-AVDD25)") (pinfunction "AVDD25") (pintype "power_in"))
    (pad "B6" smd circle locked (at 0.974 -1.625 270) (size 0.3 0.3) (layers "F.Cu" "F.Paste" "F.Mask")
      (net 4 "Net-(U1C-PCKIN)") (pinfunction "PCKIN") (pintype "input"))
    (pad "B7" smd circle locked (at 1.624 -1.625 270) (size 0.3 0.3) (layers "F.Cu" "F.Paste" "F.Mask")
      (net 50 "CSI1_D3_N") (pinfunction "CSID2_N") (pintype "output"))
    (pad "B8" smd circle locked (at 2.274 -1.625 270) (size 0.3 0.3) (layers "F.Cu" "F.Paste" "F.Mask")
      (net 51 "CSI1_D3_P") (pinfunction "CSID2_P") (pintype "output"))
    (pad "C1" smd circle locked (at -2.275 -0.975 270) (size 0.3 0.3) (layers "F.Cu" "F.Paste" "F.Mask")
      (net 80 "/Channel 1/HDMI1_CLK_P") (pinfunction "HDMIC_P") (pintype "input"))
    (pad "C2" smd circle locked (at -1.625 -0.975 270) (size 0.3 0.3) (layers "F.Cu" "F.Paste" "F.Mask")
      (net 81 "/Channel 1/HDMI1_CLK_N") (pinfunction "HDMIC_N") (pintype "input"))
    (pad "C3" smd circle locked (at -0.975 -0.975 270) (size 0.3 0.3) (layers "F.Cu" "F.Paste" "F.Mask")
      (net 19 "Net-(C27-Pad2)") (pinfunction "VDDC2") (pintype "power_in"))
    (pad "C4" smd circle locked (at -0.326 -0.975 270) (size 0.3 0.3) (layers "F.Cu" "F.Paste" "F.Mask")
      (net 2 "GND") (pinfunction "GND") (pintype "passive"))
    (pad "C5" smd circle locked (at 0.325 -0.975 270) (size 0.3 0.3) (layers "F.Cu" "F.Paste" "F.Mask")
      (net 2 "GND") (pinfunction "GND") (pintype "passive"))
    (pad "C6" smd circle locked (at 0.974 -0.975 270) (size 0.3 0.3) (layers "F.Cu" "F.Paste" "F.Mask")
      (net 7 "Net-(C10-Pad2)") (pinfunction "VDD_MIPI") (pintype "power_in"))
    (pad "C7" smd circle locked (at 1.624 -0.975 270) (size 0.3 0.3) (layers "F.Cu" "F.Paste" "F.Mask")
      (net 56 "CSI1_CLK_N") (pinfunction "CSIC_N") (pintype "output"))
    (pad "C8" smd circle locked (at 2.274 -0.975 270) (size 0.3 0.3) (layers "F.Cu" "F.Paste" "F.Mask")
      (net 57 "CSI1_CLK_P") (pinfunction "CSIC_P") (pintype "output"))
    (pad "D1" smd circle locked (at -2.275 -0.326 270) (size 0.3 0.3) (layers "F.Cu" "F.Paste" "F.Mask")
      (net 78 "/Channel 1/HDMI1_D0_P") (pinfunction "HDMID0_P") (pintype "input"))
    (pad "D2" smd circle locked (at -1.625 -0.326 270) (size 0.3 0.3) (layers "F.Cu" "F.Paste" "F.Mask")
      (net 79 "/Channel 1/HDMI1_D0_N") (pinfunction "HDMID0_N") (pintype "input"))
    (pad "D3" smd circle locked (at -0.975 -0.326 270) (size 0.3 0.3) (layers "F.Cu" "F.Paste" "F.Mask")
      (net 6 "Net-(C5-Pad1)") (pinfunction "AVDD12") (pintype "passive"))
    (pad "D4" smd circle locked (at -0.326 -0.326 270) (size 0.3 0.3) (layers "F.Cu" "F.Paste" "F.Mask")
      (net 2 "GND") (pinfunction "GND") (pintype "passive"))
    (pad "D5" smd circle locked (at 0.325 -0.326 270) (size 0.3 0.3) (layers "F.Cu" "F.Paste" "F.Mask")
      (net 2 "GND") (pinfunction "GND") (pintype "passive"))
    (pad "D6" smd circle locked (at 0.974 -0.326 270) (size 0.3 0.3) (layers "F.Cu" "F.Paste" "F.Mask")
      (net 2 "GND") (pinfunction "GND") (pintype "passive"))
    (pad "D7" smd circle locked (at 1.624 -0.326 270) (size 0.3 0.3) (layers "F.Cu" "F.Paste" "F.Mask")
      (net 52 "CSI1_D2_N") (pinfunction "CSID1_N") (pintype "output"))
    (pad "D8" smd circle locked (at 2.274 -0.326 270) (size 0.3 0.3) (layers "F.Cu" "F.Paste" "F.Mask")
      (net 53 "CSI1_D2_P") (pinfunction "CSID1_P") (pintype "output"))
    (pad "E1" smd circle locked (at -2.275 0.325 270) (size 0.3 0.3) (layers "F.Cu" "F.Paste" "F.Mask")
      (net 76 "/Channel 1/HDMI1_D1_P") (pinfunction "HDMID1_P") (pintype "input"))
    (pad "E2" smd circle locked (at -1.625 0.325 270) (size 0.3 0.3) (layers "F.Cu" "F.Paste" "F.Mask")
      (net 77 "/Channel 1/HDMI1_D1_N") (pinfunction "HDMID1_N") (pintype "input"))
    (pad "E3" smd circle locked (at -0.975 0.325 270) (size 0.3 0.3) (layers "F.Cu" "F.Paste" "F.Mask")
      (net 2 "GND") (pinfunction "GND") (pintype "passive"))
    (pad "E4" smd circle locked (at -0.326 0.325 270) (size 0.3 0.3) (layers "F.Cu" "F.Paste" "F.Mask")
      (net 2 "GND") (pinfunction "GND") (pintype "passive"))
    (pad "E5" smd circle locked (at 0.325 0.325 270) (size 0.3 0.3) (layers "F.Cu" "F.Paste" "F.Mask")
      (net 2 "GND") (pinfunction "TEST") (pintype "input"))
    (pad "E6" smd circle locked (at 0.974 0.325 270) (size 0.3 0.3) (layers "F.Cu" "F.Paste" "F.Mask")
      (net 2 "GND") (pinfunction "GND") (pintype "passive"))
    (pad "E7" smd circle locked (at 1.624 0.325 270) (size 0.3 0.3) (layers "F.Cu" "F.Paste" "F.Mask")
      (net 54 "CSI1_D1_N") (pinfunction "CSID0_N") (pintype "output"))
    (pad "E8" smd circle locked (at 2.274 0.325 270) (size 0.3 0.3) (layers "F.Cu" "F.Paste" "F.Mask")
      (net 55 "CSI1_D1_P") (pinfunction "CSID0_P") (pintype "output"))
    (pad "F1" smd circle locked (at -2.275 0.974 270) (size 0.3 0.3) (layers "F.Cu" "F.Paste" "F.Mask")
      (net 74 "/Channel 1/HDMI1_D2_P") (pinfunction "HDMID2_P") (pintype "input"))
    (pad "F2" smd circle locked (at -1.625 0.974 270) (size 0.3 0.3) (layers "F.Cu" "F.Paste" "F.Mask")
      (net 75 "/Channel 1/HDMI1_D2_N") (pinfunction "HDMID2_N") (pintype "input"))
    (pad "F3" smd circle locked (at -0.975 0.974 270) (size 0.3 0.3) (layers "F.Cu" "F.Paste" "F.Mask")
      (net 100 "/Channel 1/CH1_AVDD33") (pinfunction "AVDD33") (pintype "passive"))
    (pad "F4" smd circle locked (at -0.326 0.974 270) (size 0.3 0.3) (layers "F.Cu" "F.Paste" "F.Mask")
      (net 20 "Net-(U1B-VDDIO1)") (pinfunction "VDDIO1") (pintype "power_in"))
    (pad "F5" smd circle locked (at 0.325 0.974 270) (size 0.3 0.3) (layers "F.Cu" "F.Paste" "F.Mask")
      (net 19 "Net-(C27-Pad2)") (pinfunction "VDDC2") (pintype "passive"))
    (pad "F6" smd circle locked (at 0.974 0.974 270) (size 0.3 0.3) (layers "F.Cu" "F.Paste" "F.Mask")
      (net 7 "Net-(C10-Pad2)") (pinfunction "VDD_MIPI") (pintype "passive"))
    (pad "F7" smd circle locked (at 1.624 0.974 270) (size 0.3 0.3) (layers "F.Cu" "F.Paste" "F.Mask")
      (net 126 "unconnected-(U1C-A_SCK-PadF7)") (pinfunction "A_SCK") (pintype "output+no_connect"))
    (pad "F8" smd circle locked (at 2.274 0.974 270) (size 0.3 0.3) (layers "F.Cu" "F.Paste" "F.Mask")
      (net 127 "unconnected-(U1C-A_SD-PadF8)") (pinfunction "A_SD") (pintype "output+no_connect"))
    (pad "G1" smd circle locked (at -2.275 1.624 270) (size 0.3 0.3) (layers "F.Cu" "F.Paste" "F.Mask")
      (net 82 "/Channel 1/HDMI1_CEC") (pinfunction "CEC") (pintype "bidirectional"))
    (pad "G2" smd circle locked (at -1.625 1.624 270) (size 0.3 0.3) (layers "F.Cu" "F.Paste" "F.Mask")
      (net 8 "Net-(U1B-VDDC1)") (pinfunction "VDDC1") (pintype "power_in"))
    (pad "G3" smd circle locked (at -0.975 1.624 270) (size 0.3 0.3) (layers "F.Cu" "F.Paste" "F.Mask")
      (net 104 "/Channel 1/HDMI1_DDC_SDA_3V3") (pinfunction "DDC_SDA") (pintype "bidirectional"))
    (pad "G4" smd circle locked (at -0.326 1.624 270) (size 0.3 0.3) (layers "F.Cu" "F.Paste" "F.Mask")
      (net 68 "I2C1_SDA") (pinfunction "I2C_SDA") (pintype "bidirectional"))
    (pad "G5" smd circle locked (at 0.325 1.624 270) (size 0.3 0.3) (layers "F.Cu" "F.Paste" "F.Mask")
      (net 98 "/Channel 1/CH1_~{RST}") (pinfunction "~{RESET}") (pintype "input"))
    (pad "G6" smd circle locked (at 0.974 1.624 270) (size 0.3 0.3) (layers "F.Cu" "F.Paste" "F.Mask")
      (net 116 "Net-(U1A-EDID_SDA)") (pinfunction "EDID_SDA") (pintype "bidirectional"))
    (pad "G7" smd circle locked (at 1.624 1.624 270) (size 0.3 0.3) (layers "F.Cu" "F.Paste" "F.Mask")
      (net 128 "unconnected-(U1C-A_WFS-PadG7)") (pinfunction "A_WFS") (pintype "output+no_connect"))
    (pad "G8" smd circle locked (at 2.274 1.624 270) (size 0.3 0.3) (layers "F.Cu" "F.Paste" "F.Mask")
      (net 129 "unconnected-(U1C-A_OSCK-PadG8)") (pinfunction "A_OSCK") (pintype "output+no_connect"))
    (pad "H1" smd circle locked (at -2.275 2.274 270) (size 0.3 0.3) (layers "F.Cu" "F.Paste" "F.Mask")
      (net 115 "/Channel 1/HDMI1_HPDO") (pinfunction "HPDO") (pintype "output"))
    (pad "H2" smd circle locked (at -1.625 2.274 270) (size 0.3 0.3) (layers "F.Cu" "F.Paste" "F.Mask")
      (net 97 "/Channel 1/HDMI1_HPDI") (pinfunction "HPDI") (pintype "input"))
    (pad "H3" smd circle locked (at -0.975 2.274 270) (size 0.3 0.3) (layers "F.Cu" "F.Paste" "F.Mask")
      (net 105 "/Channel 1/HDMI1_DDC_SCL_3V3") (pinfunction "DDC_SCL") (pintype "bidirectional"))
    (pad "H4" smd circle locked (at -0.326 2.274 270) (size 0.3 0.3) (layers "F.Cu" "F.Paste" "F.Mask")
      (net 69 "I2C1_SCL") (pinfunction "I2C_SCL") (pintype "bidirectional"))
    (pad "H5" smd circle locked (at 0.325 2.274 270) (size 0.3 0.3) (layers "F.Cu" "F.Paste" "F.Mask")
      (net 15 "/Channel 1/CH1_REFCLK") (pinfunction "REFCLK") (pintype "input"))
    (pad "H6" smd circle locked (at 0.974 2.274 270) (size 0.3 0.3) (layers "F.Cu" "F.Paste" "F.Mask")
      (net 117 "Net-(U1A-EDID_SCL)") (pinfunction "EDID_SCL") (pintype "bidirectional"))
    (pad "H7" smd circle locked (at 1.624 2.274 270) (size 0.3 0.3) (layers "F.Cu" "F.Paste" "F.Mask")
      (net 21 "Net-(U1B-VDDIO2)") (pinfunction "VDDIO2") (pintype "power_in"))
    (pad "H8" smd circle locked (at 2.274 2.274 270) (size 0.3 0.3) (layers "F.Cu" "F.Paste" "F.Mask")
      (net 2 "GND") (pinfunction "GND") (pintype "passive"))
  )
	(footprint "antmicro-footprints:C_0603_1608Metric" (layer "F.Cu")
    (at 147.6 118.95 180)
    (descr "Capacitor SMD 0603")
    (tags "capacitor 0603")
    (property "Author" "Antmicro")
    (property "Dielectric" "template_dielectric")
    (property "License" "Apache-2.0")
    (property "MPN" "GRM188R61A106KE69D")
    (property "Manufacturer" "Murata")
    (property "Public" "False")
    (property "Sheetfile" "channel1.kicad_sch")
    (property "Sheetname" "Channel 1")
    (property "Val" "10u")
    (property "Voltage" "")
    (property "ki_description" "SMD Multilayer Ceramic Capacitor, 10 µF, 10 V, 0603 [1608 Metric], ± 10%, X5R, GRM Series")
    (property "ki_keywords" "0603, SMT, CAPACITOR, PASSIVE, CERAMIC, MLCC")
    (attr smd)
    (fp_text reference "C17" (at -1.09 -1.45) (layer "F.SilkS")
        (effects (font (size 0.65 0.65) (thickness 0.13)) (justify right bottom))
    )
    (fp_text value "C_10u_0603" (at 0 1.6) (layer "F.Fab")
        (effects (font (size 0.65 0.65) (thickness 0.13)) (justify right bottom))
    )
    (fp_text user "${REFERENCE}" (at -1.682 3.895) (layer "F.Fab") hide
        (effects (font (size 0.7 0.7) (thickness 0.15)) (justify right bottom))
    )
    (fp_text user "Author: Antmicro" (at -1.682 4.894) (layer "F.Fab") hide
        (effects (font (size 0.7 0.7) (thickness 0.15)) (justify right bottom))
    )
    (fp_text user "License: Apache-2.0" (at -1.682 5.895) (layer "F.Fab") hide
        (effects (font (size 0.7 0.7) (thickness 0.15)) (justify right bottom))
    )
    (fp_line (start -0.15 -0.4) (end 0.15 -0.4)
      (stroke (width 0.15) (type solid)) (layer "F.SilkS"))
    (fp_line (start -0.15 0.4) (end 0.15 0.4)
      (stroke (width 0.15) (type solid)) (layer "F.SilkS"))
    (fp_rect (start -1.25 -0.65) (end 1.25 0.65)
      (stroke (width 0.05) (type solid)) (fill none) (layer "F.CrtYd"))
    (fp_rect (start -0.8 -0.4) (end 0.8 0.4)
      (stroke (width 0.15) (type solid)) (fill none) (layer "F.Fab"))
    (pad "1" smd roundrect (at -0.7 0 180) (size 0.8 1) (layers "F.Cu" "F.Paste" "F.Mask") (roundrect_rratio 0.2)
      (net 2 "GND") (pintype "passive"))
    (pad "2" smd roundrect (at 0.7 0 180) (size 0.8 1) (layers "F.Cu" "F.Paste" "F.Mask") (roundrect_rratio 0.2)
      (net 9 "+3V3") (pintype "passive"))
  )
)
